(kicad_pcb
	(version 20260206)
	(generator "pcbnew")
	(generator_version "10.0")
	(general
		(thickness 1.6)
		(legacy_teardrops no)
	)
	(paper "A4")
	(title_block
		(title "04192023_DAF0TMB3IC0_F0TG_MB_C_brd_V02_OCP.brd")
		(comment 1 "Grand Teton / footprints 753-756 of 8354")
	)
	(layers
		(0 "F.Cu" signal "TOP")
		(4 "In1.Cu" signal "GND")
		(6 "In2.Cu" signal "IN1")
		(8 "In3.Cu" signal "GND1")
		(10 "In4.Cu" signal "IN2")
		(12 "In5.Cu" signal "GND2")
		(14 "In6.Cu" signal "IN3")
		(16 "In7.Cu" signal "GND3")
		(18 "In8.Cu" signal "VCC")
		(20 "In9.Cu" signal "VCC1")
		(22 "In10.Cu" signal "GND4")
		(24 "In11.Cu" signal "IN4")
		(26 "In12.Cu" signal "GND5")
		(28 "In13.Cu" signal "IN5")
		(30 "In14.Cu" signal "GND6")
		(32 "In15.Cu" signal "IN6")
		(34 "In16.Cu" signal "GND7")
		(2 "B.Cu" signal "BOTTOM")
		(9 "F.Adhes" user "F.Adhesive")
		(11 "B.Adhes" user "B.Adhesive")
		(13 "F.Paste" user "Package Geometry/Pastemask Top")
		(15 "B.Paste" user "Package Geometry/Pastemask Bottom")
		(5 "F.SilkS" user "Ref Des/Silkscreen Top")
		(7 "B.SilkS" user "Ref Des/Silkscreen Bottom")
		(1 "F.Mask" user "Board Geometry/Soldermask Top")
		(3 "B.Mask" user "Board Geometry/Soldermask Bottom")
		(17 "Dwgs.User" user "User.Drawings")
		(19 "Cmts.User" user "User.Comments")
		(21 "Eco1.User" user "User.Eco1")
		(23 "Eco2.User" user "User.Eco2")
		(25 "Edge.Cuts" user "Board Geometry/Outline")
		(27 "Margin" user)
		(31 "F.CrtYd" user "Package Geometry/Place Bound Top")
		(29 "B.CrtYd" user "Package Geometry/Place Bound Bottom")
		(35 "F.Fab" user "Ref Des/Assembly Top")
		(33 "B.Fab" user "Ref Des/Assembly Bottom")
	)
	(footprint ""
		(layer "F.Cu")
		(at 359.774998 -431.360072 180)
		(property "Reference" "J122"
			(at 4.688332 -9.347962 90)
			(unlocked yes)
			(layer "F.SilkS")
			(effects
				(font
					(size 0.7874 0.5842)
					(thickness 0.1524)
				)
				(justify left)
			)
		)
		(property "Value" ""
			(at 0 0 180)
			(layer "F.Fab")
			(effects
				(font
					(size 1.27 1.27)
				)
			)
		)
		(duplicate_pad_numbers_are_jumpers no)
		(fp_line
			(start 3.525012 9.6139)
			(end 3.525012 -10.489946)
			(stroke
				(width 0.1524)
				(type default)
			)
			(layer "F.SilkS")
		)
		(fp_line
			(start 3.525012 -10.489946)
			(end -3.525012 -10.489946)
			(stroke
				(width 0.1524)
				(type default)
			)
			(layer "F.SilkS")
		)
		(fp_line
			(start -3.525012 6.408928)
			(end -3.525012 9.6139)
			(stroke
				(width 0.1524)
				(type default)
			)
			(layer "F.SilkS")
		)
		(fp_line
			(start -3.525012 -10.489946)
			(end -3.525012 1.836928)
			(stroke
				(width 0.1524)
				(type default)
			)
			(layer "F.SilkS")
		)
		(fp_line
			(start 3.525012 21.310092)
			(end 3.525012 -10.489946)
			(stroke
				(width 0.1)
				(type default)
			)
			(layer "F.Fab")
		)
		(fp_line
			(start 3.525012 -10.489946)
			(end -3.525012 -10.489946)
			(stroke
				(width 0.1)
				(type default)
			)
			(layer "F.Fab")
		)
		(fp_line
			(start -3.525012 21.310092)
			(end 3.525012 21.310092)
			(stroke
				(width 0.1)
				(type default)
			)
			(layer "F.Fab")
		)
		(fp_line
			(start -3.525012 -10.489946)
			(end -3.525012 21.310092)
			(stroke
				(width 0.1)
				(type default)
			)
			(layer "F.Fab")
		)
		(pad "" np_thru_hole circle
			(at 0 -6.620002 180)
			(size 3.175 3.175)
			(drill 3.175)
			(layers "*.Cu" "*.Mask")
			(clearance 0.381)
			(thermal_gap 0.381)
		)
		(pad "" np_thru_hole circle
			(at 0 0 180)
			(size 0 0)
			(drill 3.175)
			(layers "*.Cu" "*.Mask")
			(clearance 0)
		)
		(pad "" np_thru_hole circle
			(at 0 5.130038 180)
			(size 3.175 3.175)
			(drill 3.175)
			(layers "*.Cu" "*.Mask")
			(clearance 0.381)
			(thermal_gap 0.381)
		)
		(zone
			(layers "F.Cu" "B.Cu" "In1.Cu" "In2.Cu" "In3.Cu" "In4.Cu" "In5.Cu" "In6.Cu"
				"In7.Cu" "In8.Cu" "In9.Cu" "In10.Cu" "In11.Cu" "In12.Cu" "In13.Cu" "In14.Cu"
				"In15.Cu" "In16.Cu"
			)
			(hatch none 0.5)
			(connect_pads
				(clearance 0)
			)
			(min_thickness 0.25)
			(keepout
				(tracks not_allowed)
				(vias allowed)
				(pads allowed)
				(copperpour not_allowed)
				(footprints allowed)
			)
			(placement
				(enabled no)
				(sheetname "")
			)
			(fill
				(thermal_gap 0.5)
				(thermal_bridge_width 0.5)
				(island_removal_mode 0)
			)
			(polygon
				(pts
					(arc
						(start 361.870498 -436.49011)
						(mid 357.679498 -436.49011)
						(end 361.870498 -436.49011)
					)
				)
			)
		)
		(zone
			(layers "F.Cu" "B.Cu" "In1.Cu" "In2.Cu" "In3.Cu" "In4.Cu" "In5.Cu" "In6.Cu"
				"In7.Cu" "In8.Cu" "In9.Cu" "In10.Cu" "In11.Cu" "In12.Cu" "In13.Cu" "In14.Cu"
				"In15.Cu" "In16.Cu"
			)
			(hatch none 0.5)
			(connect_pads
				(clearance 0)
			)
			(min_thickness 0.25)
			(keepout
				(tracks not_allowed)
				(vias allowed)
				(pads allowed)
				(copperpour not_allowed)
				(footprints allowed)
			)
			(placement
				(enabled no)
				(sheetname "")
			)
			(fill
				(thermal_gap 0.5)
				(thermal_bridge_width 0.5)
				(island_removal_mode 0)
			)
			(polygon
				(pts
					(arc
						(start 361.870498 -424.74007)
						(mid 357.679498 -424.74007)
						(end 361.870498 -424.74007)
					)
				)
			)
		)
		(zone
			(layers "F.Cu" "B.Cu" "In1.Cu" "In2.Cu" "In3.Cu" "In4.Cu" "In5.Cu" "In6.Cu"
				"In7.Cu" "In8.Cu" "In9.Cu" "In10.Cu" "In11.Cu" "In12.Cu" "In13.Cu" "In14.Cu"
				"In15.Cu" "In16.Cu"
			)
			(hatch none 0.5)
			(connect_pads
				(clearance 0)
			)
			(min_thickness 0.25)
			(keepout
				(tracks not_allowed)
				(vias allowed)
				(pads allowed)
				(copperpour not_allowed)
				(footprints allowed)
			)
			(placement
				(enabled no)
				(sheetname "")
			)
			(fill
				(thermal_gap 0.5)
				(thermal_bridge_width 0.5)
				(island_removal_mode 0)
			)
			(polygon
				(pts
					(arc
						(start 363.394498 -431.360072)
						(mid 356.155498 -431.360072)
						(end 363.394498 -431.360072)
					)
				)
			)
		)
	)
	(footprint ""
		(layer "F.Cu")
		(at 131.689094 -59.50712)
		(property "Reference" "U212"
			(at -0.851662 -3.495802 0)
			(unlocked yes)
			(layer "F.SilkS")
			(effects
				(font
					(size 0.7874 0.5842)
					(thickness 0.1524)
				)
				(justify left)
			)
		)
		(property "Value" ""
			(at 0 0 0)
			(layer "F.Fab")
			(effects
				(font
					(size 1.27 1.27)
				)
			)
		)
		(duplicate_pad_numbers_are_jumpers no)
		(fp_line
			(start -2.112264 -2.549906)
			(end -0.704088 -2.549906)
			(stroke
				(width 0.1524)
				(type default)
			)
			(layer "F.SilkS")
		)
		(fp_line
			(start -2.112264 2.549906)
			(end -2.112264 -2.549906)
			(stroke
				(width 0.1524)
				(type default)
			)
			(layer "F.SilkS")
		)
		(fp_line
			(start -0.704088 -2.549906)
			(end 0 -1.845818)
			(stroke
				(width 0.1524)
				(type default)
			)
			(layer "F.SilkS")
		)
		(fp_line
			(start 0 -1.845818)
			(end 0.704088 -2.549906)
			(stroke
				(width 0.1524)
				(type default)
			)
			(layer "F.SilkS")
		)
		(fp_line
			(start 0.704088 -2.549906)
			(end 2.112264 -2.549906)
			(stroke
				(width 0.1524)
				(type default)
			)
			(layer "F.SilkS")
		)
		(fp_line
			(start 2.112264 -2.549906)
			(end 2.112264 2.549906)
			(stroke
				(width 0.1524)
				(type default)
			)
			(layer "F.SilkS")
		)
		(fp_line
			(start 2.112264 2.549906)
			(end -2.112264 2.549906)
			(stroke
				(width 0.1524)
				(type default)
			)
			(layer "F.SilkS")
		)
		(fp_poly
			(pts
				(xy -4.215892 -4.104386) (xy -4.821174 -3.288538) (xy -3.702558 -3.09118)
			)
			(stroke
				(width 0)
				(type default)
			)
			(fill yes)
			(layer "F.SilkS")
		)
		(fp_line
			(start -2.249932 -2.549906)
			(end 2.249932 -2.549906)
			(stroke
				(width 0.1)
				(type default)
			)
			(layer "F.Fab")
		)
		(fp_line
			(start -2.249932 2.549906)
			(end -2.249932 -2.549906)
			(stroke
				(width 0.1)
				(type default)
			)
			(layer "F.Fab")
		)
		(fp_line
			(start 2.249932 -2.549906)
			(end 2.249932 2.549906)
			(stroke
				(width 0.1)
				(type default)
			)
			(layer "F.Fab")
		)
		(fp_line
			(start 2.249932 2.549906)
			(end -2.249932 2.549906)
			(stroke
				(width 0.1)
				(type default)
			)
			(layer "F.Fab")
		)
		(fp_poly
			(pts
				(xy -4.917186 -2.8829) (xy -4.917186 -1.8669) (xy -3.901186 -2.3749)
			)
			(stroke
				(width 0)
				(type default)
			)
			(fill yes)
			(layer "F.Fab")
		)
		(pad "1" smd rect
			(at -2.925064 -2.3749 270)
			(size 0.6096 1.3716)
			(layers "F.Cu" "F.Mask" "F.Paste")
			(net "TP_JTAG_SCM_SLOT3_R_TDO")
		)
		(pad "2" smd rect
			(at -2.925064 -1.625092 270)
			(size 0.4064 1.3716)
			(layers "F.Cu" "F.Mask" "F.Paste")
			(net "JTAG_SCM_PLD_R_TDO")
		)
		(pad "3" smd rect
			(at -2.925064 -0.975106 270)
			(size 0.4064 1.3716)
			(layers "F.Cu" "F.Mask" "F.Paste")
			(net "JTAG_SCM_TDO")
		)
		(pad "4" smd rect
			(at -2.925064 -0.32512 270)
			(size 0.4064 1.3716)
			(layers "F.Cu" "F.Mask" "F.Paste")
			(net "JTAG_SCM_PLD_R_TDO")
		)
		(pad "5" smd rect
			(at -2.925064 0.32512 270)
			(size 0.4064 1.3716)
			(layers "F.Cu" "F.Mask" "F.Paste")
			(net "JTAG_SCM_MUX_R_TDO")
		)
		(pad "6" smd rect
			(at -2.925064 0.975106 270)
			(size 0.4064 1.3716)
			(layers "F.Cu" "F.Mask" "F.Paste")
			(net "U212_EN_N")
		)
		(pad "7" smd rect
			(at -2.925064 1.625092 270)
			(size 0.4064 1.3716)
			(layers "F.Cu" "F.Mask" "F.Paste")
			(net "GND")
		)
		(pad "8" smd rect
			(at -2.925064 2.3749 270)
			(size 0.6096 1.3716)
			(layers "F.Cu" "F.Mask" "F.Paste")
			(net "GND")
		)
		(pad "9" smd rect
			(at 2.925064 2.3749 270)
			(size 0.6096 1.3716)
			(layers "F.Cu" "F.Mask" "F.Paste")
			(net "SCM_JTAG_MUX_S1")
		)
		(pad "10" smd rect
			(at 2.925064 1.625092 270)
			(size 0.4064 1.3716)
			(layers "F.Cu" "F.Mask" "F.Paste")
			(net "SCM_JTAG_MUX_S0_R2")
		)
		(pad "11" smd rect
			(at 2.925064 0.975106 270)
			(size 0.4064 1.3716)
			(layers "F.Cu" "F.Mask" "F.Paste")
			(net "JTAG_SCM_PLD_R_TDI")
		)
		(pad "12" smd rect
			(at 2.925064 0.32512 270)
			(size 0.4064 1.3716)
			(layers "F.Cu" "F.Mask" "F.Paste")
			(net "TP_JTAG_SCM_SLOT3_R_TDI")
		)
		(pad "13" smd rect
			(at 2.925064 -0.32512 270)
			(size 0.4064 1.3716)
			(layers "F.Cu" "F.Mask" "F.Paste")
			(net "JTAG_SCM_TDI")
		)
		(pad "14" smd rect
			(at 2.925064 -0.975106 270)
			(size 0.4064 1.3716)
			(layers "F.Cu" "F.Mask" "F.Paste")
			(net "JTAG_SCM_MUX_R_TDI")
		)
		(pad "15" smd rect
			(at 2.925064 -1.625092 270)
			(size 0.4064 1.3716)
			(layers "F.Cu" "F.Mask" "F.Paste")
			(net "JTAG_SCM_PLD_R_TDI")
		)
		(pad "16" smd rect
			(at 2.925064 -2.3749 270)
			(size 0.6096 1.3716)
			(layers "F.Cu" "F.Mask" "F.Paste")
			(net "P3V3_AUX")
		)
	)
	(footprint ""
		(layer "F.Cu")
		(at 111.422942 -21.7678 -90)
		(property "Reference" "R6261"
			(at 0 0 270)
			(layer "F.SilkS")
			(hide yes)
			(effects
				(font
					(size 1.27 1.27)
				)
			)
		)
		(property "Value" ""
			(at 0 0 270)
			(layer "F.Fab")
			(effects
				(font
					(size 1.27 1.27)
				)
			)
		)
		(duplicate_pad_numbers_are_jumpers no)
		(fp_line
			(start -0.7874 0.4064)
			(end -0.7874 -0.4064)
			(stroke
				(width 0.1524)
				(type default)
			)
			(layer "F.SilkS")
		)
		(fp_line
			(start 0.7874 0.4064)
			(end -0.7874 0.4064)
			(stroke
				(width 0.1524)
				(type default)
			)
			(layer "F.SilkS")
		)
		(fp_line
			(start -0.7874 -0.4064)
			(end 0.7874 -0.4064)
			(stroke
				(width 0.1524)
				(type default)
			)
			(layer "F.SilkS")
		)
		(fp_line
			(start 0.7874 -0.4064)
			(end 0.7874 0.4064)
			(stroke
				(width 0.1524)
				(type default)
			)
			(layer "F.SilkS")
		)
		(fp_line
			(start -0.67945 0.3048)
			(end -0.67945 -0.305054)
			(stroke
				(width 0.1)
				(type default)
			)
			(layer "F.Fab")
		)
		(fp_line
			(start -0.12065 0.3048)
			(end -0.67945 0.3048)
			(stroke
				(width 0.1)
				(type default)
			)
			(layer "F.Fab")
		)
		(fp_line
			(start 0.120396 0.3048)
			(end 0.120396 0.2794)
			(stroke
				(width 0.1)
				(type default)
			)
			(layer "F.Fab")
		)
		(fp_line
			(start 0.67945 0.3048)
			(end 0.120396 0.3048)
			(stroke
				(width 0.1)
				(type default)
			)
			(layer "F.Fab")
		)
		(fp_line
			(start -0.12065 0.2794)
			(end -0.12065 0.3048)
			(stroke
				(width 0.1)
				(type default)
			)
			(layer "F.Fab")
		)
		(fp_line
			(start 0.120396 0.2794)
			(end -0.12065 0.2794)
			(stroke
				(width 0.1)
				(type default)
			)
			(layer "F.Fab")
		)
		(fp_line
			(start -0.12065 -0.2794)
			(end 0.12065 -0.2794)
			(stroke
				(width 0.1)
				(type default)
			)
			(layer "F.Fab")
		)
		(fp_line
			(start 0.12065 -0.2794)
			(end 0.12065 -0.3048)
			(stroke
				(width 0.1)
				(type default)
			)
			(layer "F.Fab")
		)
		(fp_line
			(start 0.12065 -0.3048)
			(end 0.67945 -0.3048)
			(stroke
				(width 0.1)
				(type default)
			)
			(layer "F.Fab")
		)
		(fp_line
			(start 0.67945 -0.3048)
			(end 0.67945 0.3048)
			(stroke
				(width 0.1)
				(type default)
			)
			(layer "F.Fab")
		)
		(fp_line
			(start -0.67945 -0.305054)
			(end -0.12065 -0.305054)
			(stroke
				(width 0.1)
				(type default)
			)
			(layer "F.Fab")
		)
		(fp_line
			(start -0.12065 -0.305054)
			(end -0.12065 -0.2794)
			(stroke
				(width 0.1)
				(type default)
			)
			(layer "F.Fab")
		)
		(pad "1" smd circle
			(at -0.40005 0 270)
			(size 0 0)
			(layers "F.Cu" "F.Mask" "F.Paste")
			(net "USB_HUB2_TI_USB_SSRXP_DN1_MRP_VDD12")
		)
		(pad "2" smd circle
			(at 0.40005 0 270)
			(size 0 0)
			(layers "F.Cu" "F.Mask" "F.Paste")
			(net "P1V2_CPU0_USB2_DVDD12")
		)
	)
	(footprint ""
		(layer "F.Cu")
		(at 72.4662 -34.788348 180)
		(property "Reference" "R3568"
			(at 0 0 180)
			(layer "F.SilkS")
			(hide yes)
			(effects
				(font
					(size 1.27 1.27)
				)
			)
		)
		(property "Value" ""
			(at 0 0 180)
			(layer "F.Fab")
			(effects
				(font
					(size 1.27 1.27)
				)
			)
		)
		(duplicate_pad_numbers_are_jumpers no)
		(fp_line
			(start 0.7874 0.4064)
			(end -0.7874 0.4064)
			(stroke
				(width 0.1524)
				(type default)
			)
			(layer "F.SilkS")
		)
		(fp_line
			(start 0.7874 -0.4064)
			(end 0.7874 0.4064)
			(stroke
				(width 0.1524)
				(type default)
			)
			(layer "F.SilkS")
		)
		(fp_line
			(start -0.7874 0.4064)
			(end -0.7874 -0.4064)
			(stroke
				(width 0.1524)
				(type default)
			)
			(layer "F.SilkS")
		)
		(fp_line
			(start -0.7874 -0.4064)
			(end 0.7874 -0.4064)
			(stroke
				(width 0.1524)
				(type default)
			)
			(layer "F.SilkS")
		)
		(fp_line
			(start 0.67945 0.3048)
			(end 0.120396 0.3048)
			(stroke
				(width 0.1)
				(type default)
			)
			(layer "F.Fab")
		)
		(fp_line
			(start 0.67945 -0.3048)
			(end 0.67945 0.3048)
			(stroke
				(width 0.1)
				(type default)
			)
			(layer "F.Fab")
		)
		(fp_line
			(start 0.12065 -0.2794)
			(end 0.12065 -0.3048)
			(stroke
				(width 0.1)
				(type default)
			)
			(layer "F.Fab")
		)
		(fp_line
			(start 0.12065 -0.3048)
			(end 0.67945 -0.3048)
			(stroke
				(width 0.1)
				(type default)
			)
			(layer "F.Fab")
		)
		(fp_line
			(start 0.120396 0.3048)
			(end 0.120396 0.2794)
			(stroke
				(width 0.1)
				(type default)
			)
			(layer "F.Fab")
		)
		(fp_line
			(start 0.120396 0.2794)
			(end -0.12065 0.2794)
			(stroke
				(width 0.1)
				(type default)
			)
			(layer "F.Fab")
		)
		(fp_line
			(start -0.12065 0.3048)
			(end -0.67945 0.3048)
			(stroke
				(width 0.1)
				(type default)
			)
			(layer "F.Fab")
		)
		(fp_line
			(start -0.12065 0.2794)
			(end -0.12065 0.3048)
			(stroke
				(width 0.1)
				(type default)
			)
			(layer "F.Fab")
		)
		(fp_line
			(start -0.12065 -0.2794)
			(end 0.12065 -0.2794)
			(stroke
				(width 0.1)
				(type default)
			)
			(layer "F.Fab")
		)
		(fp_line
			(start -0.12065 -0.305054)
			(end -0.12065 -0.2794)
			(stroke
				(width 0.1)
				(type default)
			)
			(layer "F.Fab")
		)
		(fp_line
			(start -0.67945 0.3048)
			(end -0.67945 -0.305054)
			(stroke
				(width 0.1)
				(type default)
			)
			(layer "F.Fab")
		)
		(fp_line
			(start -0.67945 -0.305054)
			(end -0.12065 -0.305054)
			(stroke
				(width 0.1)
				(type default)
			)
			(layer "F.Fab")
		)
		(pad "1" smd circle
			(at -0.40005 0 180)
			(size 0 0)
			(layers "F.Cu" "F.Mask" "F.Paste")
			(net "SMB_INA230_3_3V3AUX_SCL_R")
		)
		(pad "2" smd circle
			(at 0.40005 0 180)
			(size 0 0)
			(layers "F.Cu" "F.Mask" "F.Paste")
			(net "SMB_INA230_3_3V3AUX_SCL_R1")
		)
	)
)
